(kicad_pcb
	(version 20260206)
	(generator "pcbnew")
	(generator_version "10.0")
	(general
		(thickness 1.6)
		(legacy_teardrops no)
	)
	(paper "A4")
	(title_block
		(title "03242023_DA0F0TMBIJ0_F0T_Motherboard_J_brd_V01_OCP.brd")
		(comment 1 "Grand Teton / footprints 2945-2950 of 6105")
	)
	(layers
		(0 "F.Cu" signal "TOP")
		(4 "In1.Cu" signal "GND")
		(6 "In2.Cu" signal "IN1")
		(8 "In3.Cu" signal "GND1")
		(10 "In4.Cu" signal "IN2")
		(12 "In5.Cu" signal "GND2")
		(14 "In6.Cu" signal "IN3")
		(16 "In7.Cu" signal "GND3")
		(18 "In8.Cu" signal "VCC")
		(20 "In9.Cu" signal "VCC1")
		(22 "In10.Cu" signal "GND4")
		(24 "In11.Cu" signal "IN4")
		(26 "In12.Cu" signal "GND5")
		(28 "In13.Cu" signal "IN5")
		(30 "In14.Cu" signal "GND6")
		(32 "In15.Cu" signal "IN6")
		(34 "In16.Cu" signal "GND7")
		(2 "B.Cu" signal "BOTTOM")
		(9 "F.Adhes" user "F.Adhesive")
		(11 "B.Adhes" user "B.Adhesive")
		(13 "F.Paste" user "Package Geometry/Pastemask Top")
		(15 "B.Paste" user "Package Geometry/Pastemask Bottom")
		(5 "F.SilkS" user "Ref Des/Silkscreen Top")
		(7 "B.SilkS" user "Ref Des/Silkscreen Bottom")
		(1 "F.Mask" user "Board Geometry/Soldermask Top")
		(3 "B.Mask" user "Board Geometry/Soldermask Bottom")
		(17 "Dwgs.User" user "User.Drawings")
		(19 "Cmts.User" user "User.Comments")
		(21 "Eco1.User" user "User.Eco1")
		(23 "Eco2.User" user "User.Eco2")
		(25 "Edge.Cuts" user "Board Geometry/Outline")
		(27 "Margin" user)
		(31 "F.CrtYd" user "Package Geometry/Place Bound Top")
		(29 "B.CrtYd" user "Package Geometry/Place Bound Bottom")
		(35 "F.Fab" user "Ref Des/Assembly Top")
		(33 "B.Fab" user "Ref Des/Assembly Bottom")
	)
	(footprint ""
		(layer "F.Cu")
		(at 398.133824 -185.96991)
		(property "Reference" "PR519"
			(at 0 0 0)
			(layer "F.SilkS")
			(hide yes)
			(effects
				(font
					(size 1.27 1.27)
				)
			)
		)
		(property "Value" ""
			(at 0 0 0)
			(layer "F.Fab")
			(effects
				(font
					(size 1.27 1.27)
				)
			)
		)
		(duplicate_pad_numbers_are_jumpers no)
		(fp_line
			(start -0.7874 -0.4064)
			(end 0.7874 -0.4064)
			(stroke
				(width 0.1524)
				(type default)
			)
			(layer "F.SilkS")
		)
		(fp_line
			(start -0.7874 0.4064)
			(end -0.7874 -0.4064)
			(stroke
				(width 0.1524)
				(type default)
			)
			(layer "F.SilkS")
		)
		(fp_line
			(start 0.7874 -0.4064)
			(end 0.7874 0.4064)
			(stroke
				(width 0.1524)
				(type default)
			)
			(layer "F.SilkS")
		)
		(fp_line
			(start 0.7874 0.4064)
			(end -0.7874 0.4064)
			(stroke
				(width 0.1524)
				(type default)
			)
			(layer "F.SilkS")
		)
		(fp_line
			(start -0.67945 -0.305054)
			(end -0.12065 -0.305054)
			(stroke
				(width 0.1)
				(type default)
			)
			(layer "F.Fab")
		)
		(fp_line
			(start -0.67945 0.3048)
			(end -0.67945 -0.305054)
			(stroke
				(width 0.1)
				(type default)
			)
			(layer "F.Fab")
		)
		(fp_line
			(start -0.12065 -0.305054)
			(end -0.12065 -0.2794)
			(stroke
				(width 0.1)
				(type default)
			)
			(layer "F.Fab")
		)
		(fp_line
			(start -0.12065 -0.2794)
			(end 0.12065 -0.2794)
			(stroke
				(width 0.1)
				(type default)
			)
			(layer "F.Fab")
		)
		(fp_line
			(start -0.12065 0.2794)
			(end -0.12065 0.3048)
			(stroke
				(width 0.1)
				(type default)
			)
			(layer "F.Fab")
		)
		(fp_line
			(start -0.12065 0.3048)
			(end -0.67945 0.3048)
			(stroke
				(width 0.1)
				(type default)
			)
			(layer "F.Fab")
		)
		(fp_line
			(start 0.120396 0.2794)
			(end -0.12065 0.2794)
			(stroke
				(width 0.1)
				(type default)
			)
			(layer "F.Fab")
		)
		(fp_line
			(start 0.120396 0.3048)
			(end 0.120396 0.2794)
			(stroke
				(width 0.1)
				(type default)
			)
			(layer "F.Fab")
		)
		(fp_line
			(start 0.12065 -0.3048)
			(end 0.67945 -0.3048)
			(stroke
				(width 0.1)
				(type default)
			)
			(layer "F.Fab")
		)
		(fp_line
			(start 0.12065 -0.2794)
			(end 0.12065 -0.3048)
			(stroke
				(width 0.1)
				(type default)
			)
			(layer "F.Fab")
		)
		(fp_line
			(start 0.67945 -0.3048)
			(end 0.67945 0.3048)
			(stroke
				(width 0.1)
				(type default)
			)
			(layer "F.Fab")
		)
		(fp_line
			(start 0.67945 0.3048)
			(end 0.120396 0.3048)
			(stroke
				(width 0.1)
				(type default)
			)
			(layer "F.Fab")
		)
		(pad "1" smd circle
			(at -0.40005 0)
			(size 0 0)
			(layers "F.Cu" "F.Mask" "F.Paste")
			(net "VSENSE_PVCCINFAON_CPU0_DN")
		)
		(pad "2" smd circle
			(at 0.40005 0)
			(size 0 0)
			(layers "F.Cu" "F.Mask" "F.Paste")
			(net "GND")
		)
	)
	(footprint ""
		(layer "F.Cu")
		(at 322.349622 -33.848548 -135)
		(property "Reference" "C609"
			(at 0 0 225)
			(layer "F.SilkS")
			(hide yes)
			(effects
				(font
					(size 1.27 1.27)
				)
			)
		)
		(property "Value" ""
			(at 0 0 225)
			(layer "F.Fab")
			(effects
				(font
					(size 1.27 1.27)
				)
			)
		)
		(duplicate_pad_numbers_are_jumpers no)
		(fp_line
			(start 0.787389 0.406267)
			(end -0.787389 0.406267)
			(stroke
				(width 0.1524)
				(type default)
			)
			(layer "F.SilkS")
		)
		(fp_line
			(start 0.787389 -0.406267)
			(end 0.787389 0.406267)
			(stroke
				(width 0.1524)
				(type default)
			)
			(layer "F.SilkS")
		)
		(fp_line
			(start -0.787389 0.406267)
			(end -0.787389 -0.406267)
			(stroke
				(width 0.1524)
				(type default)
			)
			(layer "F.SilkS")
		)
		(fp_line
			(start -0.787389 -0.406267)
			(end 0.787389 -0.406267)
			(stroke
				(width 0.1524)
				(type default)
			)
			(layer "F.SilkS")
		)
		(fp_line
			(start 0.679446 0.30479)
			(end 0.120515 0.30479)
			(stroke
				(width 0.1)
				(type default)
			)
			(layer "F.Fab")
		)
		(fp_line
			(start 0.120515 0.30479)
			(end 0.120335 0.279466)
			(stroke
				(width 0.1)
				(type default)
			)
			(layer "F.Fab")
		)
		(fp_line
			(start 0.120335 0.279466)
			(end -0.120695 0.279466)
			(stroke
				(width 0.1)
				(type default)
			)
			(layer "F.Fab")
		)
		(fp_line
			(start 0.679446 -0.30479)
			(end 0.679446 0.30479)
			(stroke
				(width 0.1)
				(type default)
			)
			(layer "F.Fab")
		)
		(fp_line
			(start -0.120515 0.30479)
			(end -0.679446 0.30479)
			(stroke
				(width 0.1)
				(type default)
			)
			(layer "F.Fab")
		)
		(fp_line
			(start -0.120695 0.279466)
			(end -0.120515 0.30479)
			(stroke
				(width 0.1)
				(type default)
			)
			(layer "F.Fab")
		)
		(fp_line
			(start 0.120695 -0.279466)
			(end 0.120515 -0.30479)
			(stroke
				(width 0.1)
				(type default)
			)
			(layer "F.Fab")
		)
		(fp_line
			(start 0.120515 -0.30479)
			(end 0.679446 -0.30479)
			(stroke
				(width 0.1)
				(type default)
			)
			(layer "F.Fab")
		)
		(fp_line
			(start -0.679446 0.30479)
			(end -0.679446 -0.305149)
			(stroke
				(width 0.1)
				(type default)
			)
			(layer "F.Fab")
		)
		(fp_line
			(start -0.120695 -0.279466)
			(end 0.120695 -0.279466)
			(stroke
				(width 0.1)
				(type default)
			)
			(layer "F.Fab")
		)
		(fp_line
			(start -0.120695 -0.304969)
			(end -0.120695 -0.279466)
			(stroke
				(width 0.1)
				(type default)
			)
			(layer "F.Fab")
		)
		(fp_line
			(start -0.679446 -0.305149)
			(end -0.120695 -0.304969)
			(stroke
				(width 0.1)
				(type default)
			)
			(layer "F.Fab")
		)
		(pad "1" smd circle
			(at -0.40005 0 225)
			(size 0 0)
			(layers "F.Cu" "F.Mask" "F.Paste")
			(net "RTC_EXT_CAP")
		)
		(pad "2" smd circle
			(at 0.40005 0 225)
			(size 0 0)
			(layers "F.Cu" "F.Mask" "F.Paste")
			(net "GND")
		)
	)
	(footprint ""
		(layer "F.Cu")
		(at 160.838642 -110.9091)
		(property "Reference" "R3132"
			(at 0 0 0)
			(layer "F.SilkS")
			(hide yes)
			(effects
				(font
					(size 1.27 1.27)
				)
			)
		)
		(property "Value" ""
			(at 0 0 0)
			(layer "F.Fab")
			(effects
				(font
					(size 1.27 1.27)
				)
			)
		)
		(duplicate_pad_numbers_are_jumpers no)
		(fp_line
			(start -0.7874 -0.4064)
			(end 0.7874 -0.4064)
			(stroke
				(width 0.1524)
				(type default)
			)
			(layer "F.SilkS")
		)
		(fp_line
			(start -0.7874 0.4064)
			(end -0.7874 -0.4064)
			(stroke
				(width 0.1524)
				(type default)
			)
			(layer "F.SilkS")
		)
		(fp_line
			(start 0.7874 -0.4064)
			(end 0.7874 0.4064)
			(stroke
				(width 0.1524)
				(type default)
			)
			(layer "F.SilkS")
		)
		(fp_line
			(start 0.7874 0.4064)
			(end -0.7874 0.4064)
			(stroke
				(width 0.1524)
				(type default)
			)
			(layer "F.SilkS")
		)
		(fp_line
			(start -0.67945 -0.305054)
			(end -0.12065 -0.305054)
			(stroke
				(width 0.1)
				(type default)
			)
			(layer "F.Fab")
		)
		(fp_line
			(start -0.67945 0.3048)
			(end -0.67945 -0.305054)
			(stroke
				(width 0.1)
				(type default)
			)
			(layer "F.Fab")
		)
		(fp_line
			(start -0.12065 -0.305054)
			(end -0.12065 -0.2794)
			(stroke
				(width 0.1)
				(type default)
			)
			(layer "F.Fab")
		)
		(fp_line
			(start -0.12065 -0.2794)
			(end 0.12065 -0.2794)
			(stroke
				(width 0.1)
				(type default)
			)
			(layer "F.Fab")
		)
		(fp_line
			(start -0.12065 0.2794)
			(end -0.12065 0.3048)
			(stroke
				(width 0.1)
				(type default)
			)
			(layer "F.Fab")
		)
		(fp_line
			(start -0.12065 0.3048)
			(end -0.67945 0.3048)
			(stroke
				(width 0.1)
				(type default)
			)
			(layer "F.Fab")
		)
		(fp_line
			(start 0.120396 0.2794)
			(end -0.12065 0.2794)
			(stroke
				(width 0.1)
				(type default)
			)
			(layer "F.Fab")
		)
		(fp_line
			(start 0.120396 0.3048)
			(end 0.120396 0.2794)
			(stroke
				(width 0.1)
				(type default)
			)
			(layer "F.Fab")
		)
		(fp_line
			(start 0.12065 -0.3048)
			(end 0.67945 -0.3048)
			(stroke
				(width 0.1)
				(type default)
			)
			(layer "F.Fab")
		)
		(fp_line
			(start 0.12065 -0.2794)
			(end 0.12065 -0.3048)
			(stroke
				(width 0.1)
				(type default)
			)
			(layer "F.Fab")
		)
		(fp_line
			(start 0.67945 -0.3048)
			(end 0.67945 0.3048)
			(stroke
				(width 0.1)
				(type default)
			)
			(layer "F.Fab")
		)
		(fp_line
			(start 0.67945 0.3048)
			(end 0.120396 0.3048)
			(stroke
				(width 0.1)
				(type default)
			)
			(layer "F.Fab")
		)
		(pad "1" smd circle
			(at -0.40005 0)
			(size 0 0)
			(layers "F.Cu" "F.Mask" "F.Paste")
			(net "GND")
		)
		(pad "2" smd circle
			(at 0.40005 0)
			(size 0 0)
			(layers "F.Cu" "F.Mask" "F.Paste")
			(net "FM_OCP_SFF_PWR_GOOD")
		)
	)
	(footprint ""
		(layer "F.Cu")
		(at 15.436596 -391.183876)
		(property "Reference" "R3275"
			(at 0 0 0)
			(layer "F.SilkS")
			(hide yes)
			(effects
				(font
					(size 1.27 1.27)
				)
			)
		)
		(property "Value" ""
			(at 0 0 0)
			(layer "F.Fab")
			(effects
				(font
					(size 1.27 1.27)
				)
			)
		)
		(duplicate_pad_numbers_are_jumpers no)
		(fp_line
			(start -0.7874 -0.4064)
			(end 0.7874 -0.4064)
			(stroke
				(width 0.1524)
				(type default)
			)
			(layer "F.SilkS")
		)
		(fp_line
			(start -0.7874 0.4064)
			(end -0.7874 -0.4064)
			(stroke
				(width 0.1524)
				(type default)
			)
			(layer "F.SilkS")
		)
		(fp_line
			(start 0.7874 -0.4064)
			(end 0.7874 0.4064)
			(stroke
				(width 0.1524)
				(type default)
			)
			(layer "F.SilkS")
		)
		(fp_line
			(start 0.7874 0.4064)
			(end -0.7874 0.4064)
			(stroke
				(width 0.1524)
				(type default)
			)
			(layer "F.SilkS")
		)
		(fp_line
			(start -0.67945 -0.305054)
			(end -0.12065 -0.305054)
			(stroke
				(width 0.1)
				(type default)
			)
			(layer "F.Fab")
		)
		(fp_line
			(start -0.67945 0.3048)
			(end -0.67945 -0.305054)
			(stroke
				(width 0.1)
				(type default)
			)
			(layer "F.Fab")
		)
		(fp_line
			(start -0.12065 -0.305054)
			(end -0.12065 -0.2794)
			(stroke
				(width 0.1)
				(type default)
			)
			(layer "F.Fab")
		)
		(fp_line
			(start -0.12065 -0.2794)
			(end 0.12065 -0.2794)
			(stroke
				(width 0.1)
				(type default)
			)
			(layer "F.Fab")
		)
		(fp_line
			(start -0.12065 0.2794)
			(end -0.12065 0.3048)
			(stroke
				(width 0.1)
				(type default)
			)
			(layer "F.Fab")
		)
		(fp_line
			(start -0.12065 0.3048)
			(end -0.67945 0.3048)
			(stroke
				(width 0.1)
				(type default)
			)
			(layer "F.Fab")
		)
		(fp_line
			(start 0.120396 0.2794)
			(end -0.12065 0.2794)
			(stroke
				(width 0.1)
				(type default)
			)
			(layer "F.Fab")
		)
		(fp_line
			(start 0.120396 0.3048)
			(end 0.120396 0.2794)
			(stroke
				(width 0.1)
				(type default)
			)
			(layer "F.Fab")
		)
		(fp_line
			(start 0.12065 -0.3048)
			(end 0.67945 -0.3048)
			(stroke
				(width 0.1)
				(type default)
			)
			(layer "F.Fab")
		)
		(fp_line
			(start 0.12065 -0.2794)
			(end 0.12065 -0.3048)
			(stroke
				(width 0.1)
				(type default)
			)
			(layer "F.Fab")
		)
		(fp_line
			(start 0.67945 -0.3048)
			(end 0.67945 0.3048)
			(stroke
				(width 0.1)
				(type default)
			)
			(layer "F.Fab")
		)
		(fp_line
			(start 0.67945 0.3048)
			(end 0.120396 0.3048)
			(stroke
				(width 0.1)
				(type default)
			)
			(layer "F.Fab")
		)
		(pad "1" smd circle
			(at -0.40005 0)
			(size 0 0)
			(layers "F.Cu" "F.Mask" "F.Paste")
			(net "P3V3_AUX")
		)
		(pad "2" smd circle
			(at 0.40005 0)
			(size 0 0)
			(layers "F.Cu" "F.Mask" "F.Paste")
			(net "FM_P2E_FGA")
		)
	)
	(footprint ""
		(layer "F.Cu")
		(at 423.089324 -149.239224 -90)
		(property "Reference" "PC176"
			(at 0 0 270)
			(layer "F.SilkS")
			(hide yes)
			(effects
				(font
					(size 1.27 1.27)
				)
			)
		)
		(property "Value" ""
			(at 0 0 270)
			(layer "F.Fab")
			(effects
				(font
					(size 1.27 1.27)
				)
			)
		)
		(duplicate_pad_numbers_are_jumpers no)
		(fp_line
			(start -0.7874 0.4064)
			(end -0.7874 -0.4064)
			(stroke
				(width 0.1524)
				(type default)
			)
			(layer "F.SilkS")
		)
		(fp_line
			(start 0.7874 0.4064)
			(end -0.7874 0.4064)
			(stroke
				(width 0.1524)
				(type default)
			)
			(layer "F.SilkS")
		)
		(fp_line
			(start -0.7874 -0.4064)
			(end 0.7874 -0.4064)
			(stroke
				(width 0.1524)
				(type default)
			)
			(layer "F.SilkS")
		)
		(fp_line
			(start 0.7874 -0.4064)
			(end 0.7874 0.4064)
			(stroke
				(width 0.1524)
				(type default)
			)
			(layer "F.SilkS")
		)
		(fp_line
			(start -0.67945 0.3048)
			(end -0.67945 -0.305054)
			(stroke
				(width 0.1)
				(type default)
			)
			(layer "F.Fab")
		)
		(fp_line
			(start -0.12065 0.3048)
			(end -0.67945 0.3048)
			(stroke
				(width 0.1)
				(type default)
			)
			(layer "F.Fab")
		)
		(fp_line
			(start 0.120396 0.3048)
			(end 0.120396 0.2794)
			(stroke
				(width 0.1)
				(type default)
			)
			(layer "F.Fab")
		)
		(fp_line
			(start 0.67945 0.3048)
			(end 0.120396 0.3048)
			(stroke
				(width 0.1)
				(type default)
			)
			(layer "F.Fab")
		)
		(fp_line
			(start -0.12065 0.2794)
			(end -0.12065 0.3048)
			(stroke
				(width 0.1)
				(type default)
			)
			(layer "F.Fab")
		)
		(fp_line
			(start 0.120396 0.2794)
			(end -0.12065 0.2794)
			(stroke
				(width 0.1)
				(type default)
			)
			(layer "F.Fab")
		)
		(fp_line
			(start -0.12065 -0.2794)
			(end 0.12065 -0.2794)
			(stroke
				(width 0.1)
				(type default)
			)
			(layer "F.Fab")
		)
		(fp_line
			(start 0.12065 -0.2794)
			(end 0.12065 -0.3048)
			(stroke
				(width 0.1)
				(type default)
			)
			(layer "F.Fab")
		)
		(fp_line
			(start 0.12065 -0.3048)
			(end 0.67945 -0.3048)
			(stroke
				(width 0.1)
				(type default)
			)
			(layer "F.Fab")
		)
		(fp_line
			(start 0.67945 -0.3048)
			(end 0.67945 0.3048)
			(stroke
				(width 0.1)
				(type default)
			)
			(layer "F.Fab")
		)
		(fp_line
			(start -0.67945 -0.305054)
			(end -0.12065 -0.305054)
			(stroke
				(width 0.1)
				(type default)
			)
			(layer "F.Fab")
		)
		(fp_line
			(start -0.12065 -0.305054)
			(end -0.12065 -0.2794)
			(stroke
				(width 0.1)
				(type default)
			)
			(layer "F.Fab")
		)
		(pad "1" smd circle
			(at -0.40005 0 270)
			(size 0 0)
			(layers "F.Cu" "F.Mask" "F.Paste")
			(net "SW_P12V_PVCCINFAON_CPU0_FLT")
		)
		(pad "2" smd circle
			(at 0.40005 0 270)
			(size 0 0)
			(layers "F.Cu" "F.Mask" "F.Paste")
			(net "GND")
		)
	)
	(footprint ""
		(layer "F.Cu")
		(at 69.923406 -154.36469)
		(property "Reference" "PC1596"
			(at 0 0 0)
			(layer "F.SilkS")
			(hide yes)
			(effects
				(font
					(size 1.27 1.27)
				)
			)
		)
		(property "Value" ""
			(at 0 0 0)
			(layer "F.Fab")
			(effects
				(font
					(size 1.27 1.27)
				)
			)
		)
		(duplicate_pad_numbers_are_jumpers no)
		(fp_line
			(start 2.750058 0.999998)
			(end -2.750058 0.999998)
			(stroke
				(width 0.1524)
				(type default)
			)
			(layer "F.SilkS")
		)
		(fp_circle
			(center 0 0.999998)
			(end 2.750058 0.999998)
			(stroke
				(width 0.1524)
				(type default)
			)
			(fill no)
			(layer "F.SilkS")
		)
		(fp_poly
			(pts
				(arc
					(start 2.750058 0.999998)
					(mid 0 3.750056)
					(end -2.750058 0.999998)
				)
			)
			(stroke
				(width 0)
				(type default)
			)
			(fill yes)
			(layer "F.SilkS")
		)
		(fp_circle
			(center 0 0.999998)
			(end 2.750058 0.999998)
			(stroke
				(width 0.1)
				(type default)
			)
			(fill no)
			(layer "F.Fab")
		)
		(pad "1" thru_hole rect
			(at 0 0)
			(size 1.5748 1.5748)
			(drill 1.0668)
			(layers "*.Cu" "*.Mask")
			(remove_unused_layers no)
			(net "PVCCINFAON_CPU1")
			(clearance 0)
			(padstack
				(mode front_inner_back)
				(layer "Inner"
					(shape circle)
					(size 1.5748 1.5748)
					(clearance 0)
				)
				(layer "B.Cu"
					(shape rect)
					(size 1.5748 1.5748)
					(clearance 0)
				)
			)
		)
		(pad "2" thru_hole circle
			(at 0 1.999996)
			(size 1.5748 1.5748)
			(drill 1.0668)
			(layers "*.Cu" "*.Mask")
			(remove_unused_layers no)
			(net "GND")
			(clearance 0)
		)
	)
)
